# BASEBOARD_FAB2 (Tioga Pass) — schematic netlist excerpt (pin names and nets, part order shuffled) for the footprints in the layout excerpt that follows; sources: Cadence DE-HDL packaged netlist, KiCad conversion of Wiwynn_Tioga_Pass_MB.brd

R8A13  RES  150.0 1% CHIP  pkg 0402  page 112 : A = P1V05_PCH_STBY ; B = XDP_TDI
R7G10  RES  2.26K 1.0% CHIP  pkg 0402  page 215 : A = VR_PVDDQ_ABC_XADDR2 ; B = GND
R25W69  RES  33.2 1% CHIP  pkg 0402  page 146 : A = LPC_LAD1_IO1 ; B = LPC_LAD1_IO1_R

(kicad_pcb
	(version 20260206)
	(generator "pcbnew")
	(generator_version "10.0")
	(general
		(thickness 1.6)
		(legacy_teardrops no)
	)
	(paper "A4")
	(title_block
		(title "Wiwynn_Tioga_Pass_MB.brd")
		(comment 1 "Tioga Pass / footprints 144-146 of 4770")
	)
	(layers
		(0 "F.Cu" signal "TOP")
		(4 "In1.Cu" signal "L2GND")
		(6 "In2.Cu" signal "L3")
		(8 "In3.Cu" signal "L4GND")
		(10 "In4.Cu" signal "L5")
		(12 "In5.Cu" signal "L6GND")
		(14 "In6.Cu" signal "L7VCC")
		(16 "In7.Cu" signal "L8VCC")
		(18 "In8.Cu" signal "L9GND")
		(20 "In9.Cu" signal "L10")
		(22 "In10.Cu" signal "L11GND")
		(24 "In11.Cu" signal "L12")
		(26 "In12.Cu" signal "L13GND")
		(2 "B.Cu" signal "BOTTOM")
		(9 "F.Adhes" user "F.Adhesive")
		(11 "B.Adhes" user "B.Adhesive")
		(13 "F.Paste" user "Package Geometry/Pastemask Top")
		(15 "B.Paste" user "Package Geometry/Pastemask Bottom")
		(5 "F.SilkS" user "Ref Des/Silkscreen Top")
		(7 "B.SilkS" user "Ref Des/Silkscreen Bottom")
		(1 "F.Mask" user "Board Geometry/Soldermask Top")
		(3 "B.Mask" user "Board Geometry/Soldermask Bottom")
		(17 "Dwgs.User" user "User.Drawings")
		(19 "Cmts.User" user "User.Comments")
		(21 "Eco1.User" user "User.Eco1")
		(23 "Eco2.User" user "User.Eco2")
		(25 "Edge.Cuts" user "Board Geometry/Outline")
		(27 "Margin" user)
		(31 "F.CrtYd" user "Package Geometry/Place Bound Top")
		(29 "B.CrtYd" user "Package Geometry/Place Bound Bottom")
		(35 "F.Fab" user "Ref Des/Assembly Top")
		(33 "B.Fab" user "Ref Des/Assembly Bottom")
	)
	(footprint ""
		(layer "F.Cu")
		(at 379.222 -88.2015)
		(property "Reference" "R25W69"
			(at -0.8382 -0.67818 0)
			(unlocked yes)
			(layer "F.SilkS")
			(effects
				(font
					(size 0.4064 0.254)
					(thickness 0.1524)
				)
				(justify left)
			)
		)
		(property "Value" ""
			(at 0 0 0)
			(layer "F.Fab")
			(effects
				(font
					(size 1.27 1.27)
				)
			)
		)
		(duplicate_pad_numbers_are_jumpers no)
		(fp_poly
			(pts
				(xy -0.2794 -0.1016) (xy 0.2794 -0.1016) (xy 0.2794 0.9906) (xy -0.2794 0.9906)
			)
			(stroke
				(width 0)
				(type default)
			)
			(fill no)
			(layer "F.CrtYd")
		)
		(fp_line
			(start -0.2794 -0.1016)
			(end -0.2794 0.9906)
			(stroke
				(width 0.1)
				(type default)
			)
			(layer "F.Fab")
		)
		(fp_line
			(start -0.2794 0.9906)
			(end 0.2794 0.9906)
			(stroke
				(width 0.1)
				(type default)
			)
			(layer "F.Fab")
		)
		(fp_line
			(start 0.2794 -0.1016)
			(end -0.2794 -0.1016)
			(stroke
				(width 0.1)
				(type default)
			)
			(layer "F.Fab")
		)
		(fp_line
			(start 0.2794 0.9906)
			(end 0.2794 -0.1016)
			(stroke
				(width 0.1)
				(type default)
			)
			(layer "F.Fab")
		)
		(pad "1" smd rect
			(at 0 0)
			(size 0.508 0.508)
			(layers "F.Cu" "F.Mask" "F.Paste")
			(net "LPC_LAD1_IO1")
		)
		(pad "2" smd rect
			(at 0 0.889)
			(size 0.508 0.508)
			(layers "F.Cu" "F.Mask" "F.Paste")
			(net "LPC_LAD1_IO1_R")
		)
		(zone
			(layer "F.Cu")
			(hatch none 0.5)
			(connect_pads
				(clearance 0)
			)
			(min_thickness 0.25)
			(keepout
				(tracks allowed)
				(vias not_allowed)
				(pads allowed)
				(copperpour not_allowed)
				(footprints allowed)
			)
			(placement
				(enabled no)
				(sheetname "")
			)
			(fill
				(thermal_gap 0.5)
				(thermal_bridge_width 0.5)
				(island_removal_mode 0)
			)
			(polygon
				(pts
					(xy 378.968 -87.9475) (xy 379.476 -87.9475) (xy 379.476 -87.5665) (xy 378.968 -87.5665)
				)
			)
		)
		(zone
			(layer "F.Cu")
			(hatch none 0.5)
			(connect_pads
				(clearance 0)
			)
			(min_thickness 0.25)
			(keepout
				(tracks not_allowed)
				(vias allowed)
				(pads allowed)
				(copperpour not_allowed)
				(footprints allowed)
			)
			(placement
				(enabled no)
				(sheetname "")
			)
			(fill
				(thermal_gap 0.5)
				(thermal_bridge_width 0.5)
				(island_removal_mode 0)
			)
			(polygon
				(pts
					(xy 378.968 -87.5665) (xy 379.476 -87.5665) (xy 379.476 -87.9475) (xy 378.968 -87.9475)
				)
			)
		)
	)
	(footprint ""
		(layer "F.Cu")
		(at 349.123 -12.827 90)
		(property "Reference" "R7G10"
			(at 0 0 90)
			(layer "F.SilkS")
			(hide yes)
			(effects
				(font
					(size 1.27 1.27)
				)
			)
		)
		(property "Value" ""
			(at 0 0 90)
			(layer "F.Fab")
			(effects
				(font
					(size 1.27 1.27)
				)
			)
		)
		(duplicate_pad_numbers_are_jumpers no)
		(fp_poly
			(pts
				(xy -0.2794 -0.1016) (xy 0.2794 -0.1016) (xy 0.2794 0.9906) (xy -0.2794 0.9906)
			)
			(stroke
				(width 0)
				(type default)
			)
			(fill no)
			(layer "F.CrtYd")
		)
		(fp_line
			(start 0.2794 -0.1016)
			(end -0.2794 -0.1016)
			(stroke
				(width 0.1)
				(type default)
			)
			(layer "F.Fab")
		)
		(fp_line
			(start -0.2794 -0.1016)
			(end -0.2794 0.9906)
			(stroke
				(width 0.1)
				(type default)
			)
			(layer "F.Fab")
		)
		(fp_line
			(start 0.2794 0.9906)
			(end 0.2794 -0.1016)
			(stroke
				(width 0.1)
				(type default)
			)
			(layer "F.Fab")
		)
		(fp_line
			(start -0.2794 0.9906)
			(end 0.2794 0.9906)
			(stroke
				(width 0.1)
				(type default)
			)
			(layer "F.Fab")
		)
		(pad "1" smd rect
			(at 0 0 90)
			(size 0.508 0.508)
			(layers "F.Cu" "F.Mask" "F.Paste")
			(net "VR_PVDDQ_ABC_XADDR2")
		)
		(pad "2" smd rect
			(at 0 0.889 90)
			(size 0.508 0.508)
			(layers "F.Cu" "F.Mask" "F.Paste")
			(net "GND")
		)
		(zone
			(layer "F.Cu")
			(hatch none 0.5)
			(connect_pads
				(clearance 0)
			)
			(min_thickness 0.25)
			(keepout
				(tracks allowed)
				(vias not_allowed)
				(pads allowed)
				(copperpour not_allowed)
				(footprints allowed)
			)
			(placement
				(enabled no)
				(sheetname "")
			)
			(fill
				(thermal_gap 0.5)
				(thermal_bridge_width 0.5)
				(island_removal_mode 0)
			)
			(polygon
				(pts
					(xy 349.377 -12.573) (xy 349.377 -13.081) (xy 349.758 -13.081) (xy 349.758 -12.573)
				)
			)
		)
		(zone
			(layer "F.Cu")
			(hatch none 0.5)
			(connect_pads
				(clearance 0)
			)
			(min_thickness 0.25)
			(keepout
				(tracks not_allowed)
				(vias allowed)
				(pads allowed)
				(copperpour not_allowed)
				(footprints allowed)
			)
			(placement
				(enabled no)
				(sheetname "")
			)
			(fill
				(thermal_gap 0.5)
				(thermal_bridge_width 0.5)
				(island_removal_mode 0)
			)
			(polygon
				(pts
					(xy 349.758 -12.573) (xy 349.758 -13.081) (xy 349.377 -13.081) (xy 349.377 -12.573)
				)
			)
		)
	)
	(footprint ""
		(layer "F.Cu")
		(at 413.521652 -135.636)
		(property "Reference" "R8A13"
			(at 0 0 0)
			(layer "F.SilkS")
			(hide yes)
			(effects
				(font
					(size 1.27 1.27)
				)
			)
		)
		(property "Value" ""
			(at 0 0 0)
			(layer "F.Fab")
			(effects
				(font
					(size 1.27 1.27)
				)
			)
		)
		(duplicate_pad_numbers_are_jumpers no)
		(fp_poly
			(pts
				(xy -0.2794 -0.1016) (xy 0.2794 -0.1016) (xy 0.2794 0.9906) (xy -0.2794 0.9906)
			)
			(stroke
				(width 0)
				(type default)
			)
			(fill no)
			(layer "F.CrtYd")
		)
		(fp_line
			(start -0.2794 -0.1016)
			(end -0.2794 0.9906)
			(stroke
				(width 0.1)
				(type default)
			)
			(layer "F.Fab")
		)
		(fp_line
			(start -0.2794 0.9906)
			(end 0.2794 0.9906)
			(stroke
				(width 0.1)
				(type default)
			)
			(layer "F.Fab")
		)
		(fp_line
			(start 0.2794 -0.1016)
			(end -0.2794 -0.1016)
			(stroke
				(width 0.1)
				(type default)
			)
			(layer "F.Fab")
		)
		(fp_line
			(start 0.2794 0.9906)
			(end 0.2794 -0.1016)
			(stroke
				(width 0.1)
				(type default)
			)
			(layer "F.Fab")
		)
		(pad "1" smd rect
			(at 0 0)
			(size 0.508 0.508)
			(layers "F.Cu" "F.Mask" "F.Paste")
			(net "P1V05_PCH_STBY")
		)
		(pad "2" smd rect
			(at 0 0.889)
			(size 0.508 0.508)
			(layers "F.Cu" "F.Mask" "F.Paste")
			(net "XDP_TDI")
		)
		(zone
			(layer "F.Cu")
			(hatch none 0.5)
			(connect_pads
				(clearance 0)
			)
			(min_thickness 0.25)
			(keepout
				(tracks allowed)
				(vias not_allowed)
				(pads allowed)
				(copperpour not_allowed)
				(footprints allowed)
			)
			(placement
				(enabled no)
				(sheetname "")
			)
			(fill
				(thermal_gap 0.5)
				(thermal_bridge_width 0.5)
				(island_removal_mode 0)
			)
			(polygon
				(pts
					(xy 413.267652 -135.382) (xy 413.775652 -135.382) (xy 413.775652 -135.001) (xy 413.267652 -135.001)
				)
			)
		)
		(zone
			(layer "F.Cu")
			(hatch none 0.5)
			(connect_pads
				(clearance 0)
			)
			(min_thickness 0.25)
			(keepout
				(tracks not_allowed)
				(vias allowed)
				(pads allowed)
				(copperpour not_allowed)
				(footprints allowed)
			)
			(placement
				(enabled no)
				(sheetname "")
			)
			(fill
				(thermal_gap 0.5)
				(thermal_bridge_width 0.5)
				(island_removal_mode 0)
			)
			(polygon
				(pts
					(xy 413.267652 -135.001) (xy 413.775652 -135.001) (xy 413.775652 -135.382) (xy 413.267652 -135.382)
				)
			)
		)
	)
)
